# S9S_MB_2U (Grand Teton) — schematic netlist excerpt (pin names and nets, part order shuffled) for the footprints in the layout excerpt that follows; sources: Cadence DE-HDL packaged netlist, KiCad conversion of 03242023_DA0F0TMBIJ0_F0T_Motherboard_J_brd_V01_OCP.brd

J25  SCONN288_ADR50017P130CC  SCONN288_ADR50017-P130CC IO  pkg DDR288S_1-1VXB  page 106
  VIN_BULK0  = P12V_S3_AUX_CPU1_NVDIMM
  RFU0  = TP_CHE_CPU1_DIMM1_FRU_0
  VIN_MGMT  = P3V3_AUX
  HSCL  = I3C_SPD_DDREFGH_CPU1_LVC1_SCL_R
  HSDA  = I3C_SPD_DDREFGH_CPU1_LVC1_SDA
  VSS0  = GND
  DQ0_A  = M_E_CPU1_SA_DQ<0>
  VSS1  = GND
  DQ1_A  = M_E_CPU1_SA_DQ<1>
  VSS2  = GND
  DQS0_A_T  = M_E_CPU1_SA_DQS_DP<0>
  DQS0_A_C  = M_E_CPU1_SA_DQS_DN<0>
  VSS3  = GND
  DQ4_A  = M_E_CPU1_SA_DQ<4>
  VSS4  = GND
  DQ5_A  = M_E_CPU1_SA_DQ<5>
  VSS5  = GND
  DQ8_A  = M_E_CPU1_SA_DQ<8>
  VSS6  = GND
  DQ9_A  = M_E_CPU1_SA_DQ<9>
  VSS7  = GND
  DQS1_A_T  = M_E_CPU1_SA_DQS_DP<1>
  DQS1_A_C  = M_E_CPU1_SA_DQS_DN<1>
  VSS8  = GND
  DQ12_A  = M_E_CPU1_SA_DQ<12>
  VSS9  = GND
  DQ13_A  = M_E_CPU1_SA_DQ<13>
  VSS10  = GND
  DQ16_A  = M_E_CPU1_SA_DQ<16>
  VSS11  = GND
  DQ17_A  = M_E_CPU1_SA_DQ<17>
  VSS12  = GND
  DQS2_A_T  = M_E_CPU1_SA_DQS_DP<2>
  DQS2_A_C  = M_E_CPU1_SA_DQS_DN<2>
  VSS13  = GND
  DQ20_A  = M_E_CPU1_SA_DQ<20>
  VSS14  = GND
  DQ21_A  = M_E_CPU1_SA_DQ<21>
  VSS15  = GND
  DQ24_A  = M_E_CPU1_SA_DQ<24>
  VSS16  = GND
  DQ25_A  = M_E_CPU1_SA_DQ<25>
  VSS17  = GND
  DQS3_A_T  = M_E_CPU1_SA_DQS_DP<3>
  DQS3_A_C  = M_E_CPU1_SA_DQS_DN<3>
  VSS18  = GND
  DQ28_A  = M_E_CPU1_SA_DQ<28>
  VSS19  = GND
  DQ29_A  = M_E_CPU1_SA_DQ<29>
  VSS20  = GND
  CB0_A  = M_E_CPU1_SA_CB<0>
  VSS21  = GND
  CB1_A  = M_E_CPU1_SA_CB<1>
  VSS22  = GND
  DQS4_A_T  = M_E_CPU1_SA_DQS_DP<4>
  DQS4_A_C  = M_E_CPU1_SA_DQS_DN<4>
  VSS23  = GND
  CB4_A  = M_E_CPU1_SA_CB<4>
  VSS24  = GND
  CB5_A  = M_E_CPU1_SA_CB<5>
  VSS25  = GND
  ALERT_N  = M_E_CPU1_ALERT_N
  VSS26  = GND
  CS0_A_N  = M_E_CPU1_SA_CS_N<0>
  VSS27  = GND
  CA0_A  = M_E_CPU1_SA_CA<0>
  VSS28  = GND
  CA2_A  = M_E_CPU1_SA_CA<2>
  VSS29  = GND
  CA4_A  = M_E_CPU1_SA_CA<4>
  VSS30  = GND
  CA6_A  = M_E_CPU1_SA_CA<6>
  VSS31  = GND
  PAR_A  = M_E_CPU1_SA_PAR
  VSS32  = GND
  CA0_B  = M_E_CPU1_SB_CA<0>
  VSS33  = GND
  CA2_B  = M_E_CPU1_SB_CA<2>
  VSS34  = GND
  CA4_B  = M_E_CPU1_SB_CA<4>
  VSS35  = GND
  CA6_B  = M_E_CPU1_SB_CA<6>
  VSS36  = GND
  CS0_B_N  = M_E_CPU1_SB_CS_N<0>
  VSS37  = GND
  \lbd||rsp_a_n\  = M_E_CPU1_SA_RSP<0>
  \lbs||rsp_b_n\  = M_E_CPU1_SB_RSP<0>
  VSS38  = GND
  CB4_B  = M_E_CPU1_SB_CB<4>
  VSS39  = GND
  CB5_B  = M_E_CPU1_SB_CB<5>
  VSS40  = GND
  \dqs9_b_t||tdqs9_b_t||dbi4_b_n\  = M_E_CPU1_SB_DQS_DP<9>
  \dqs9_b_c||tdqs9_b_c\  = M_E_CPU1_SB_DQS_DN<9>
  VSS41  = GND
  CB0_B  = M_E_CPU1_SB_CB<0>
  VSS42  = GND
  CB1_B  = M_E_CPU1_SB_CB<1>
  VSS43  = GND
  DQ0_B  = M_E_CPU1_SB_DQ<0>
  VSS44  = GND
  DQ1_B  = M_E_CPU1_SB_DQ<1>
  VSS45  = GND
  DQS0_B_T  = M_E_CPU1_SB_DQS_DP<0>
  DQS0_B_C  = M_E_CPU1_SB_DQS_DN<0>
  VSS46  = GND
  DQ4_B  = M_E_CPU1_SB_DQ<4>
  VSS47  = GND
  DQ5_B  = M_E_CPU1_SB_DQ<5>
  VSS48  = GND
  DQ8_B  = M_E_CPU1_SB_DQ<8>
  VSS49  = GND
  DQ9_B  = M_E_CPU1_SB_DQ<9>
  VSS50  = GND
  DQS1_B_T  = M_E_CPU1_SB_DQS_DP<1>
  DQS1_B_C  = M_E_CPU1_SB_DQS_DN<1>
  VSS51  = GND
  DQ12_B  = M_E_CPU1_SB_DQ<12>
  VSS52  = GND
  DQ13_B  = M_E_CPU1_SB_DQ<13>
  VSS53  = GND
  DQ16_B  = M_E_CPU1_SB_DQ<16>
  VSS54  = GND
  DQ17_B  = M_E_CPU1_SB_DQ<17>
  VSS55  = GND
  DQS2_B_T  = M_E_CPU1_SB_DQS_DP<2>
  DQS2_B_C  = M_E_CPU1_SB_DQS_DN<2>
  VSS56  = GND
  DQ20_B  = M_E_CPU1_SB_DQ<20>
  VSS57  = GND
  DQ21_B  = M_E_CPU1_SB_DQ<21>
  VSS58  = GND
  DQ24_B  = M_E_CPU1_SB_DQ<24>
  VSS59  = GND
  DQ25_B  = M_E_CPU1_SB_DQ<25>
  VSS60  = GND
  DQS3_B_T  = M_E_CPU1_SB_DQS_DP<3>
  DQS3_B_C  = M_E_CPU1_SB_DQS_DN<3>
  VSS61  = GND
  DQ28_B  = M_E_CPU1_SB_DQ<28>
  VSS62  = GND
  DQ29_B  = M_E_CPU1_SB_DQ<29>
  VSS63  = GND
  RFU1  = TP_CHE_CPU1_DIMM1_FRU_1
  VIN_BULK1  = P12V_S3_AUX_CPU1_NVDIMM
  VIN_BULK2  = P12V_S3_AUX_CPU1_NVDIMM
  \pwr_good||fail_n\  = PWRGD_CHE_CPU1_DIMM1
  HSA  = PD_CHE_CPU1_DIMM1_SAA
  RFU2  = TP_CHE_CPU1_DIMM1_FRU_2
  RFU3  = TP_CHE_CPU1_DIMM1_FRU_3
  VSS64  = GND
  DQ2_A  = M_E_CPU1_SA_DQ<2>
  VSS65  = GND
  DQ3_A  = M_E_CPU1_SA_DQ<3>
  VSS66  = GND
  \dqs5_a_c||tdqs5_a_c||dqs5_a_t||tdqs5_a_t\  = M_E_CPU1_SA_DQS_DN<5>
  \dqs5_a_t||tdqs5_a_t\  = M_E_CPU1_SA_DQS_DP<5>
  VSS67  = GND
  DQ6_A  = M_E_CPU1_SA_DQ<6>
  VSS68  = GND
  DQ7_A  = M_E_CPU1_SA_DQ<7>
  VSS69  = GND
  DQ10_A  = M_E_CPU1_SA_DQ<10>
  VSS70  = GND
  DQ11_A  = M_E_CPU1_SA_DQ<11>
  VSS71  = GND
  \dqs6_a_c||tdqs6_a_c||dqs6_a_t||tdqs6_a_t\  = M_E_CPU1_SA_DQS_DN<6>
  \dqs6_a_t||tdqs6_a_t\  = M_E_CPU1_SA_DQS_DP<6>
  VSS72  = GND
  DQ14_A  = M_E_CPU1_SA_DQ<14>
  VSS73  = GND
  DQ15_A  = M_E_CPU1_SA_DQ<15>
  VSS74  = GND
  DQ18_A  = M_E_CPU1_SA_DQ<18>
  VSS75  = GND
  DQ19_A  = M_E_CPU1_SA_DQ<19>
  VSS76  = GND
  \dqs7_a_c||tdqs7_a_c\  = M_E_CPU1_SA_DQS_DN<7>
  \dqs7_a_t||tdqs7_a_t\  = M_E_CPU1_SA_DQS_DP<7>
  VSS77  = GND
  DQ22_A  = M_E_CPU1_SA_DQ<22>
  VSS78  = GND
  DQ23_A  = M_E_CPU1_SA_DQ<23>
  VSS79  = GND
  DQ26_A  = M_E_CPU1_SA_DQ<26>
  VSS80  = GND
  DQ27_A  = M_E_CPU1_SA_DQ<27>
  VSS81  = GND
  \dqs8_a_c||tdqs8_a_c\  = M_E_CPU1_SA_DQS_DN<8>
  \dqs8_a_t||tdqs8_a_t\  = M_E_CPU1_SA_DQS_DP<8>
  VSS82  = GND
  DQ30_A  = M_E_CPU1_SA_DQ<30>
  VSS83  = GND
  DQ31_A  = M_E_CPU1_SA_DQ<31>
  VSS84  = GND
  CB2_A  = M_E_CPU1_SA_CB<2>
  VSS85  = GND
  CB3_A  = M_E_CPU1_SA_CB<3>
  VSS86  = GND
  \dqs9_a_c||tdqs9_a_c\  = M_E_CPU1_SA_DQS_DN<9>
  \dqs9_a_t||tdqs9_a_t\  = M_E_CPU1_SA_DQS_DP<9>
  VSS87  = GND
  CB6_A  = M_E_CPU1_SA_CB<6>
  VSS88  = GND
  CB7_A  = M_E_CPU1_SA_CB<7>
  VSS89  = GND
  RESET_N  = RST_M_EF_CPU1_FPGA_N
  VSS90  = GND
  CS1_A_N  = M_E_CPU1_SA_CS_N<1>
  VSS91  = GND
  CA1_A  = M_E_CPU1_SA_CA<1>
  VSS92  = GND
  CA3_A  = M_E_CPU1_SA_CA<3>
  VSS93  = GND
  CA5_A  = M_E_CPU1_SA_CA<5>
  VSS94  = GND
  CK_T  = M_E_CPU1_CLK_DP<0>
  CK_C  = M_E_CPU1_CLK_DN<0>
  VSS95  = GND
  RFU4  = TP_CHE_CPU1_DIMM1_FRU_4
  CA1_B  = M_E_CPU1_SB_CA<1>
  VSS96  = GND
  CA3_B  = M_E_CPU1_SB_CA<3>
  VSS97  = GND
  CA5_B  = M_E_CPU1_SB_CA<5>
  VSS98  = GND
  PAR_B  = M_E_CPU1_SB_PAR
  VSS99  = GND
  CS1_B_N  = M_E_CPU1_SB_CS_N<1>
  VSS100  = GND
  RFU5  = TP_CHE_CPU1_DIMM1_FRU_5
  RFU6  = TP_CHE_CPU1_DIMM1_FRU_6
  VSS101  = GND
  CB6_B  = M_E_CPU1_SB_CB<6>
  VSS102  = GND
  CB7_B  = M_E_CPU1_SB_CB<7>
  VSS103  = GND
  DQS4_B_C  = M_E_CPU1_SB_DQS_DN<4>
  DQS4_B_T  = M_E_CPU1_SB_DQS_DP<4>
  VSS104  = GND
  CB2_B  = M_E_CPU1_SB_CB<2>
  VSS105  = GND
  CB3_B  = M_E_CPU1_SB_CB<3>
  VSS106  = GND
  DQ2_B  = M_E_CPU1_SB_DQ<2>
  VSS107  = GND
  DQ3_B  = M_E_CPU1_SB_DQ<3>
  VSS108  = GND
  \dqs5_b_c||tdqs5_b_c\  = M_E_CPU1_SB_DQS_DN<5>
  \dqs5_b_t||tdqs5_b_t\  = M_E_CPU1_SB_DQS_DP<5>
  VSS109  = GND
  DQ6_B  = M_E_CPU1_SB_DQ<6>
  VSS110  = GND
  DQ7_B  = M_E_CPU1_SB_DQ<7>
  VSS111  = GND
  DQ10_B  = M_E_CPU1_SB_DQ<10>
  VSS112  = GND
  DQ11_B  = M_E_CPU1_SB_DQ<11>
  VSS113  = GND
  \dqs6_b_c||tdqs6_b_c\  = M_E_CPU1_SB_DQS_DN<6>
  \dqs6_b_t||tdqs6_b_t\  = M_E_CPU1_SB_DQS_DP<6>
  VSS114  = GND
  DQ14_B  = M_E_CPU1_SB_DQ<14>
  VSS115  = GND
  DQ15_B  = M_E_CPU1_SB_DQ<15>
  VSS116  = GND
  DQ18_B  = M_E_CPU1_SB_DQ<18>
  VSS117  = GND
  DQ19_B  = M_E_CPU1_SB_DQ<19>
  VSS118  = GND
  \dqs7_b_c||tdqs7_b_c\  = M_E_CPU1_SB_DQS_DN<7>
  \dqs7_b_t||tdqs7_b_t\  = M_E_CPU1_SB_DQS_DP<7>
  VSS119  = GND
  DQ22_B  = M_E_CPU1_SB_DQ<22>
  VSS120  = GND
  DQ23_B  = M_E_CPU1_SB_DQ<23>
  VSS121  = GND
  DQ26_B  = M_E_CPU1_SB_DQ<26>
  VSS122  = GND
  DQ27_B  = M_E_CPU1_SB_DQ<27>
  VSS123  = GND
  \dqs8_b_c||tdqs8_b_c\  = M_E_CPU1_SB_DQS_DN<8>
  \dqs8_b_t||tdqs8_b_t\  = M_E_CPU1_SB_DQS_DP<8>
  VSS124  = GND
  DQ30_B  = M_E_CPU1_SB_DQ<30>
  VSS125  = GND
  DQ31_B  = M_E_CPU1_SB_DQ<31>
  VSS126  = GND
  G1  = GND
  G2  = GND
  G3  = GND

(kicad_pcb
	(version 20260206)
	(generator "pcbnew")
	(generator_version "10.0")
	(general
		(thickness 1.6)
		(legacy_teardrops no)
	)
	(paper "A4")
	(title_block
		(title "03242023_DA0F0TMBIJ0_F0T_Motherboard_J_brd_V01_OCP.brd")
		(comment 1 "Grand Teton / footprint 2539 of 6105 (J25), pads 92-137 of 291")
	)
	(layers
		(0 "F.Cu" signal "TOP")
		(4 "In1.Cu" signal "GND")
		(6 "In2.Cu" signal "IN1")
		(8 "In3.Cu" signal "GND1")
		(10 "In4.Cu" signal "IN2")
		(12 "In5.Cu" signal "GND2")
		(14 "In6.Cu" signal "IN3")
		(16 "In7.Cu" signal "GND3")
		(18 "In8.Cu" signal "VCC")
		(20 "In9.Cu" signal "VCC1")
		(22 "In10.Cu" signal "GND4")
		(24 "In11.Cu" signal "IN4")
		(26 "In12.Cu" signal "GND5")
		(28 "In13.Cu" signal "IN5")
		(30 "In14.Cu" signal "GND6")
		(32 "In15.Cu" signal "IN6")
		(34 "In16.Cu" signal "GND7")
		(2 "B.Cu" signal "BOTTOM")
		(9 "F.Adhes" user "F.Adhesive")
		(11 "B.Adhes" user "B.Adhesive")
		(13 "F.Paste" user "Package Geometry/Pastemask Top")
		(15 "B.Paste" user "Package Geometry/Pastemask Bottom")
		(5 "F.SilkS" user "Ref Des/Silkscreen Top")
		(7 "B.SilkS" user "Ref Des/Silkscreen Bottom")
		(1 "F.Mask" user "Board Geometry/Soldermask Top")
		(3 "B.Mask" user "Board Geometry/Soldermask Bottom")
		(17 "Dwgs.User" user "User.Drawings")
		(19 "Cmts.User" user "User.Comments")
		(21 "Eco1.User" user "User.Eco1")
		(23 "Eco2.User" user "User.Eco2")
		(25 "Edge.Cuts" user "Board Geometry/Outline")
		(27 "Margin" user)
		(31 "F.CrtYd" user "Package Geometry/Place Bound Top")
		(29 "B.CrtYd" user "Package Geometry/Place Bound Bottom")
		(35 "F.Fab" user "Ref Des/Assembly Top")
		(33 "B.Fab" user "Ref Des/Assembly Bottom")
	)
	(footprint ""
		(layer "F.Cu")
		(at 168.40708 -258.091686)
		(property "Reference" "J25"
			(at -3.683 -81.702148 0)
			(unlocked yes)
			(layer "F.SilkS")
			(effects
				(font
					(size 0.7874 0.5842)
					(thickness 0.1524)
				)
				(justify left)
			)
		)
		(property "Value" ""
			(at 0 0 0)
			(layer "F.Fab")
			(effects
				(font
					(size 1.27 1.27)
				)
			)
		)
		(duplicate_pad_numbers_are_jumpers no)
		(pad "92" smd rect
			(at -2.050034 19.12493 270)
			(size 0.519938 1.4986)
			(layers "F.Cu" "F.Mask" "F.Paste")
			(net "GND")
		)
		(pad "93" smd rect
			(at -2.050034 19.975068 270)
			(size 0.519938 1.4986)
			(layers "F.Cu" "F.Mask" "F.Paste")
			(net "M_E_CPU1_SB_DQS_DP<9>")
		)
		(pad "94" smd rect
			(at -2.050034 20.824952 270)
			(size 0.519938 1.4986)
			(layers "F.Cu" "F.Mask" "F.Paste")
			(net "M_E_CPU1_SB_DQS_DN<9>")
		)
		(pad "95" smd rect
			(at -2.050034 21.67509 270)
			(size 0.519938 1.4986)
			(layers "F.Cu" "F.Mask" "F.Paste")
			(net "GND")
		)
		(pad "96" smd rect
			(at -2.050034 22.524974 270)
			(size 0.519938 1.4986)
			(layers "F.Cu" "F.Mask" "F.Paste")
			(net "M_E_CPU1_SB_CB<0>")
		)
		(pad "97" smd rect
			(at -2.050034 23.375112 270)
			(size 0.519938 1.4986)
			(layers "F.Cu" "F.Mask" "F.Paste")
			(net "GND")
		)
		(pad "98" smd rect
			(at -2.050034 24.224996 270)
			(size 0.519938 1.4986)
			(layers "F.Cu" "F.Mask" "F.Paste")
			(net "M_E_CPU1_SB_CB<1>")
		)
		(pad "99" smd rect
			(at -2.050034 25.07488 270)
			(size 0.519938 1.4986)
			(layers "F.Cu" "F.Mask" "F.Paste")
			(net "GND")
		)
		(pad "100" smd rect
			(at -2.050034 25.925018 270)
			(size 0.519938 1.4986)
			(layers "F.Cu" "F.Mask" "F.Paste")
			(net "M_E_CPU1_SB_DQ<0>")
		)
		(pad "101" smd rect
			(at -2.050034 26.774902 270)
			(size 0.519938 1.4986)
			(layers "F.Cu" "F.Mask" "F.Paste")
			(net "GND")
		)
		(pad "102" smd rect
			(at -2.050034 27.62504 270)
			(size 0.519938 1.4986)
			(layers "F.Cu" "F.Mask" "F.Paste")
			(net "M_E_CPU1_SB_DQ<1>")
		)
		(pad "103" smd rect
			(at -2.050034 28.474924 270)
			(size 0.519938 1.4986)
			(layers "F.Cu" "F.Mask" "F.Paste")
			(net "GND")
		)
		(pad "104" smd rect
			(at -2.050034 29.325062 270)
			(size 0.519938 1.4986)
			(layers "F.Cu" "F.Mask" "F.Paste")
			(net "M_E_CPU1_SB_DQS_DP<0>")
		)
		(pad "105" smd rect
			(at -2.050034 30.174946 270)
			(size 0.519938 1.4986)
			(layers "F.Cu" "F.Mask" "F.Paste")
			(net "M_E_CPU1_SB_DQS_DN<0>")
		)
		(pad "106" smd rect
			(at -2.050034 31.025084 270)
			(size 0.519938 1.4986)
			(layers "F.Cu" "F.Mask" "F.Paste")
			(net "GND")
		)
		(pad "107" smd rect
			(at -2.050034 31.874968 270)
			(size 0.519938 1.4986)
			(layers "F.Cu" "F.Mask" "F.Paste")
			(net "M_E_CPU1_SB_DQ<4>")
		)
		(pad "108" smd rect
			(at -2.050034 32.725106 270)
			(size 0.519938 1.4986)
			(layers "F.Cu" "F.Mask" "F.Paste")
			(net "GND")
		)
		(pad "109" smd rect
			(at -2.050034 33.57499 270)
			(size 0.519938 1.4986)
			(layers "F.Cu" "F.Mask" "F.Paste")
			(net "M_E_CPU1_SB_DQ<5>")
		)
		(pad "110" smd rect
			(at -2.050034 34.425128 270)
			(size 0.519938 1.4986)
			(layers "F.Cu" "F.Mask" "F.Paste")
			(net "GND")
		)
		(pad "111" smd rect
			(at -2.050034 35.275012 270)
			(size 0.519938 1.4986)
			(layers "F.Cu" "F.Mask" "F.Paste")
			(net "M_E_CPU1_SB_DQ<8>")
		)
		(pad "112" smd rect
			(at -2.050034 36.124896 270)
			(size 0.519938 1.4986)
			(layers "F.Cu" "F.Mask" "F.Paste")
			(net "GND")
		)
		(pad "113" smd rect
			(at -2.050034 36.975034 270)
			(size 0.519938 1.4986)
			(layers "F.Cu" "F.Mask" "F.Paste")
			(net "M_E_CPU1_SB_DQ<9>")
		)
		(pad "114" smd rect
			(at -2.050034 37.824918 270)
			(size 0.519938 1.4986)
			(layers "F.Cu" "F.Mask" "F.Paste")
			(net "GND")
		)
		(pad "115" smd rect
			(at -2.050034 38.675056 270)
			(size 0.519938 1.4986)
			(layers "F.Cu" "F.Mask" "F.Paste")
			(net "M_E_CPU1_SB_DQS_DP<1>")
		)
		(pad "116" smd rect
			(at -2.050034 39.52494 270)
			(size 0.519938 1.4986)
			(layers "F.Cu" "F.Mask" "F.Paste")
			(net "M_E_CPU1_SB_DQS_DN<1>")
		)
		(pad "117" smd rect
			(at -2.050034 40.375078 270)
			(size 0.519938 1.4986)
			(layers "F.Cu" "F.Mask" "F.Paste")
			(net "GND")
		)
		(pad "118" smd rect
			(at -2.050034 41.224962 270)
			(size 0.519938 1.4986)
			(layers "F.Cu" "F.Mask" "F.Paste")
			(net "M_E_CPU1_SB_DQ<12>")
		)
		(pad "119" smd rect
			(at -2.050034 42.0751 270)
			(size 0.519938 1.4986)
			(layers "F.Cu" "F.Mask" "F.Paste")
			(net "GND")
		)
		(pad "120" smd rect
			(at -2.050034 42.924984 270)
			(size 0.519938 1.4986)
			(layers "F.Cu" "F.Mask" "F.Paste")
			(net "M_E_CPU1_SB_DQ<13>")
		)
		(pad "121" smd rect
			(at -2.050034 43.775122 270)
			(size 0.519938 1.4986)
			(layers "F.Cu" "F.Mask" "F.Paste")
			(net "GND")
		)
		(pad "122" smd rect
			(at -2.050034 44.625006 270)
			(size 0.519938 1.4986)
			(layers "F.Cu" "F.Mask" "F.Paste")
			(net "M_E_CPU1_SB_DQ<16>")
		)
		(pad "123" smd rect
			(at -2.050034 45.47489 270)
			(size 0.519938 1.4986)
			(layers "F.Cu" "F.Mask" "F.Paste")
			(net "GND")
		)
		(pad "124" smd rect
			(at -2.050034 46.325028 270)
			(size 0.519938 1.4986)
			(layers "F.Cu" "F.Mask" "F.Paste")
			(net "M_E_CPU1_SB_DQ<17>")
		)
		(pad "125" smd rect
			(at -2.050034 47.174912 270)
			(size 0.519938 1.4986)
			(layers "F.Cu" "F.Mask" "F.Paste")
			(net "GND")
		)
		(pad "126" smd rect
			(at -2.050034 48.02505 270)
			(size 0.519938 1.4986)
			(layers "F.Cu" "F.Mask" "F.Paste")
			(net "M_E_CPU1_SB_DQS_DP<2>")
		)
		(pad "127" smd rect
			(at -2.050034 48.874934 270)
			(size 0.519938 1.4986)
			(layers "F.Cu" "F.Mask" "F.Paste")
			(net "M_E_CPU1_SB_DQS_DN<2>")
		)
		(pad "128" smd rect
			(at -2.050034 49.725072 270)
			(size 0.519938 1.4986)
			(layers "F.Cu" "F.Mask" "F.Paste")
			(net "GND")
		)
		(pad "129" smd rect
			(at -2.050034 50.574956 270)
			(size 0.519938 1.4986)
			(layers "F.Cu" "F.Mask" "F.Paste")
			(net "M_E_CPU1_SB_DQ<20>")
		)
		(pad "130" smd rect
			(at -2.050034 51.425094 270)
			(size 0.519938 1.4986)
			(layers "F.Cu" "F.Mask" "F.Paste")
			(net "GND")
		)
		(pad "131" smd rect
			(at -2.050034 52.274978 270)
			(size 0.519938 1.4986)
			(layers "F.Cu" "F.Mask" "F.Paste")
			(net "M_E_CPU1_SB_DQ<21>")
		)
		(pad "132" smd rect
			(at -2.050034 53.125116 270)
			(size 0.519938 1.4986)
			(layers "F.Cu" "F.Mask" "F.Paste")
			(net "GND")
		)
		(pad "133" smd rect
			(at -2.050034 53.975 270)
			(size 0.519938 1.4986)
			(layers "F.Cu" "F.Mask" "F.Paste")
			(net "M_E_CPU1_SB_DQ<24>")
		)
		(pad "134" smd rect
			(at -2.050034 54.824884 270)
			(size 0.519938 1.4986)
			(layers "F.Cu" "F.Mask" "F.Paste")
			(net "GND")
		)
		(pad "135" smd rect
			(at -2.050034 55.675022 270)
			(size 0.519938 1.4986)
			(layers "F.Cu" "F.Mask" "F.Paste")
			(net "M_E_CPU1_SB_DQ<25>")
		)
		(pad "136" smd rect
			(at -2.050034 56.524906 270)
			(size 0.519938 1.4986)
			(layers "F.Cu" "F.Mask" "F.Paste")
			(net "GND")
		)
		(pad "137" smd rect
			(at -2.050034 57.375044 270)
			(size 0.519938 1.4986)
			(layers "F.Cu" "F.Mask" "F.Paste")
			(net "M_E_CPU1_SB_DQS_DP<3>")
		)
	)
)
